(kicad_pcb
	(version 20260206)
	(generator "pcbnew")
	(generator_version "10.0")
	(general
		(thickness 1.6)
		(legacy_teardrops no)
	)
	(paper "A4")
	(title_block
		(title "01162023_DA0F0TEBIF0_F0T_Expander_BD_F_brd_V02_OCP.brd")
		(comment 1 "Grand Teton / footprints 718-723 of 9728")
	)
	(layers
		(0 "F.Cu" signal "TOP")
		(4 "In1.Cu" signal "GND")
		(6 "In2.Cu" signal "VCC")
		(8 "In3.Cu" signal "VCC1")
		(10 "In4.Cu" signal "GND1")
		(12 "In5.Cu" signal "IN1")
		(14 "In6.Cu" signal "GND2")
		(16 "In7.Cu" signal "IN2")
		(18 "In8.Cu" signal "GND3")
		(20 "In9.Cu" signal "IN3")
		(22 "In10.Cu" signal "GND4")
		(24 "In11.Cu" signal "IN4")
		(26 "In12.Cu" signal "GND5")
		(28 "In13.Cu" signal "IN5")
		(30 "In14.Cu" signal "GND6")
		(32 "In15.Cu" signal "IN6")
		(34 "In16.Cu" signal "GND7")
		(2 "B.Cu" signal "BOTTOM")
		(9 "F.Adhes" user "F.Adhesive")
		(11 "B.Adhes" user "B.Adhesive")
		(13 "F.Paste" user "Package Geometry/Pastemask Top")
		(15 "B.Paste" user "Package Geometry/Pastemask Bottom")
		(5 "F.SilkS" user "Ref Des/Silkscreen Top")
		(7 "B.SilkS" user "Ref Des/Silkscreen Bottom")
		(1 "F.Mask" user "Board Geometry/Soldermask Top")
		(3 "B.Mask" user "Board Geometry/Soldermask Bottom")
		(17 "Dwgs.User" user "User.Drawings")
		(19 "Cmts.User" user "User.Comments")
		(21 "Eco1.User" user "User.Eco1")
		(23 "Eco2.User" user "User.Eco2")
		(25 "Edge.Cuts" user "Board Geometry/Outline")
		(27 "Margin" user)
		(31 "F.CrtYd" user "Package Geometry/Place Bound Top")
		(29 "B.CrtYd" user "Package Geometry/Place Bound Bottom")
		(35 "F.Fab" user "Ref Des/Assembly Top")
		(33 "B.Fab" user "Ref Des/Assembly Bottom")
	)
	(footprint ""
		(layer "F.Cu")
		(at 362.03128 -125.144784 180)
		(property "Reference" "PU51"
			(at 2.769362 -4.61264 0)
			(unlocked yes)
			(layer "F.SilkS")
			(effects
				(font
					(size 0.7874 0.5842)
					(thickness 0.1524)
				)
				(justify left)
			)
		)
		(property "Value" ""
			(at 0 0 180)
			(layer "F.Fab")
			(effects
				(font
					(size 1.27 1.27)
				)
			)
		)
		(duplicate_pad_numbers_are_jumpers no)
		(fp_line
			(start 1.943608 1.549908)
			(end -1.943608 1.549908)
			(stroke
				(width 0.1524)
				(type default)
			)
			(layer "F.SilkS")
		)
		(fp_line
			(start 1.943608 -1.549908)
			(end 1.943608 1.549908)
			(stroke
				(width 0.1524)
				(type default)
			)
			(layer "F.SilkS")
		)
		(fp_line
			(start -1.943608 1.549908)
			(end -1.943608 -1.549908)
			(stroke
				(width 0.1524)
				(type default)
			)
			(layer "F.SilkS")
		)
		(fp_line
			(start -1.943608 -1.549908)
			(end 1.943608 -1.549908)
			(stroke
				(width 0.1524)
				(type default)
			)
			(layer "F.SilkS")
		)
		(fp_poly
			(pts
				(xy -2.019808 -1.549908) (xy -1.257808 -1.549908) (xy -1.257808 -1.880108) (xy -2.019808 -1.880108)
			)
			(stroke
				(width 0)
				(type default)
			)
			(fill yes)
			(layer "F.SilkS")
		)
		(fp_line
			(start 1.549908 1.549908)
			(end -1.549908 1.549908)
			(stroke
				(width 0.1)
				(type default)
			)
			(layer "F.Fab")
		)
		(fp_line
			(start 1.549908 -1.549908)
			(end 1.549908 1.549908)
			(stroke
				(width 0.1)
				(type default)
			)
			(layer "F.Fab")
		)
		(fp_line
			(start -1.549908 1.549908)
			(end -1.549908 -1.549908)
			(stroke
				(width 0.1)
				(type default)
			)
			(layer "F.Fab")
		)
		(fp_line
			(start -1.549908 -1.549908)
			(end 1.549908 -1.549908)
			(stroke
				(width 0.1)
				(type default)
			)
			(layer "F.Fab")
		)
		(fp_poly
			(pts
				(xy -2.019808 -1.549908) (xy -1.257808 -1.549908) (xy -1.257808 -1.880108) (xy -2.019808 -1.880108)
			)
			(stroke
				(width 0)
				(type default)
			)
			(fill yes)
			(layer "F.Fab")
		)
		(pad "1" smd rect
			(at -1.500124 -1.249934 90)
			(size 0.2794 0.6096)
			(layers "F.Cu" "F.Mask" "F.Paste")
			(net "P3V3_NIC6")
		)
		(pad "2" smd rect
			(at -1.500124 -0.750062 90)
			(size 0.2794 0.6096)
			(layers "F.Cu" "F.Mask" "F.Paste")
			(net "P3V3_NIC6")
		)
		(pad "3" smd rect
			(at -1.500124 -0.249936 90)
			(size 0.2794 0.6096)
			(layers "F.Cu" "F.Mask" "F.Paste")
			(net "P3V3_NIC6")
		)
		(pad "4" smd rect
			(at -1.500124 0.249936 90)
			(size 0.2794 0.6096)
			(layers "F.Cu" "F.Mask" "F.Paste")
			(net "P3V3_NIC6")
		)
		(pad "5" smd rect
			(at -1.500124 0.750062 90)
			(size 0.2794 0.6096)
			(layers "F.Cu" "F.Mask" "F.Paste")
			(net "P3V3_NIC6")
		)
		(pad "6" smd rect
			(at -1.500124 1.249934 90)
			(size 0.2794 0.6096)
			(layers "F.Cu" "F.Mask" "F.Paste")
			(net "GND")
		)
		(pad "7" smd rect
			(at 1.500124 1.249934 90)
			(size 0.2794 0.6096)
			(layers "F.Cu" "F.Mask" "F.Paste")
			(net "P3V3_NIC6_SS")
		)
		(pad "8" smd rect
			(at 1.500124 0.750062 90)
			(size 0.2794 0.6096)
			(layers "F.Cu" "F.Mask" "F.Paste")
			(net "PWRGD_P3V3_NIC6")
		)
		(pad "9" smd rect
			(at 1.500124 0.249936 90)
			(size 0.2794 0.6096)
			(layers "F.Cu" "F.Mask" "F.Paste")
			(net "P3V3_NIC6_OCP")
		)
		(pad "10" smd rect
			(at 1.500124 -0.249936 90)
			(size 0.2794 0.6096)
			(layers "F.Cu" "F.Mask" "F.Paste")
			(net "P5V_AUX")
		)
		(pad "11" smd rect
			(at 1.500124 -0.750062 90)
			(size 0.2794 0.6096)
			(layers "F.Cu" "F.Mask" "F.Paste")
			(net "HP_NIC6_EN")
		)
		(pad "12" smd rect
			(at 1.500124 -1.249934 90)
			(size 0.2794 0.6096)
			(layers "F.Cu" "F.Mask" "F.Paste")
			(net "P3V3_AUX")
		)
		(pad "13" smd rect
			(at 0 0 180)
			(size 1.9812 2.7178)
			(layers "F.Cu" "F.Mask" "F.Paste")
			(net "P3V3_AUX")
		)
		(zone
			(layer "F.Cu")
			(hatch none 0.5)
			(connect_pads
				(clearance 0)
			)
			(min_thickness 0.25)
			(keepout
				(tracks not_allowed)
				(vias allowed)
				(pads allowed)
				(copperpour not_allowed)
				(footprints allowed)
			)
			(placement
				(enabled no)
				(sheetname "")
			)
			(fill
				(thermal_gap 0.5)
				(thermal_bridge_width 0.5)
				(island_removal_mode 0)
			)
			(polygon
				(pts
					(xy 360.88828 -123.595384) (xy 360.88828 -123.722384) (xy 360.88828 -126.694184) (xy 360.88828 -126.694692)
					(xy 363.17428 -126.694692) (xy 363.17428 -126.694184) (xy 363.17428 -126.567184) (xy 363.17428 -125.144784)
					(xy 363.07268 -125.144784) (xy 363.07268 -126.567184) (xy 360.98988 -126.567184) (xy 360.98988 -123.722384)
					(xy 363.07268 -123.722384) (xy 363.07268 -125.119384) (xy 363.17428 -125.119384) (xy 363.17428 -123.722384)
					(xy 363.17428 -123.595384) (xy 363.17428 -123.594876) (xy 360.88828 -123.594876)
				)
			)
		)
	)
	(footprint ""
		(layer "F.Cu")
		(at 480.851972 -521.86459 180)
		(property "Reference" "J30_OTH"
			(at -3.2385 -1.402334 0)
			(unlocked yes)
			(layer "B.SilkS")
			(effects
				(font
					(size 0.7874 0.5842)
					(thickness 0.1524)
				)
				(justify mirror)
			)
		)
		(property "Value" ""
			(at 0 0 180)
			(layer "F.Fab")
			(effects
				(font
					(size 1.27 1.27)
				)
			)
		)
		(duplicate_pad_numbers_are_jumpers no)
		(pad "1" thru_hole circle
			(at 0 0 180)
			(size 0.4572 0.4572)
			(drill 0.2032)
			(layers "*.Cu" "*.Mask")
			(remove_unused_layers no)
			(net "Net_9106")
			(clearance 0.127)
			(thermal_gap 0.127)
			(padstack
				(mode front_inner_back)
				(layer "Inner"
					(shape circle)
					(size 0.4572 0.4572)
					(clearance 0.127)
				)
				(layer "B.Cu"
					(shape circle)
					(size 0.508 0.508)
					(clearance 0.1016)
				)
			)
		)
	)
	(footprint ""
		(layer "F.Cu")
		(at 10.11047 -122.931428 180)
		(property "Reference" "PC481"
			(at 0 0 180)
			(layer "F.SilkS")
			(hide yes)
			(effects
				(font
					(size 1.27 1.27)
				)
			)
		)
		(property "Value" ""
			(at 0 0 180)
			(layer "F.Fab")
			(effects
				(font
					(size 1.27 1.27)
				)
			)
		)
		(duplicate_pad_numbers_are_jumpers no)
		(fp_line
			(start 0.7874 0.4064)
			(end -0.7874 0.4064)
			(stroke
				(width 0.1524)
				(type default)
			)
			(layer "F.SilkS")
		)
		(fp_line
			(start 0.7874 -0.4064)
			(end 0.7874 0.4064)
			(stroke
				(width 0.1524)
				(type default)
			)
			(layer "F.SilkS")
		)
		(fp_line
			(start -0.7874 0.4064)
			(end -0.7874 -0.4064)
			(stroke
				(width 0.1524)
				(type default)
			)
			(layer "F.SilkS")
		)
		(fp_line
			(start -0.7874 -0.4064)
			(end 0.7874 -0.4064)
			(stroke
				(width 0.1524)
				(type default)
			)
			(layer "F.SilkS")
		)
		(fp_line
			(start 0.67945 0.3048)
			(end 0.120396 0.3048)
			(stroke
				(width 0.1)
				(type default)
			)
			(layer "F.Fab")
		)
		(fp_line
			(start 0.67945 -0.3048)
			(end 0.67945 0.3048)
			(stroke
				(width 0.1)
				(type default)
			)
			(layer "F.Fab")
		)
		(fp_line
			(start 0.12065 -0.2794)
			(end 0.12065 -0.3048)
			(stroke
				(width 0.1)
				(type default)
			)
			(layer "F.Fab")
		)
		(fp_line
			(start 0.12065 -0.3048)
			(end 0.67945 -0.3048)
			(stroke
				(width 0.1)
				(type default)
			)
			(layer "F.Fab")
		)
		(fp_line
			(start 0.120396 0.3048)
			(end 0.120396 0.2794)
			(stroke
				(width 0.1)
				(type default)
			)
			(layer "F.Fab")
		)
		(fp_line
			(start 0.120396 0.2794)
			(end -0.12065 0.2794)
			(stroke
				(width 0.1)
				(type default)
			)
			(layer "F.Fab")
		)
		(fp_line
			(start -0.12065 0.3048)
			(end -0.67945 0.3048)
			(stroke
				(width 0.1)
				(type default)
			)
			(layer "F.Fab")
		)
		(fp_line
			(start -0.12065 0.2794)
			(end -0.12065 0.3048)
			(stroke
				(width 0.1)
				(type default)
			)
			(layer "F.Fab")
		)
		(fp_line
			(start -0.12065 -0.2794)
			(end 0.12065 -0.2794)
			(stroke
				(width 0.1)
				(type default)
			)
			(layer "F.Fab")
		)
		(fp_line
			(start -0.12065 -0.305054)
			(end -0.12065 -0.2794)
			(stroke
				(width 0.1)
				(type default)
			)
			(layer "F.Fab")
		)
		(fp_line
			(start -0.67945 0.3048)
			(end -0.67945 -0.305054)
			(stroke
				(width 0.1)
				(type default)
			)
			(layer "F.Fab")
		)
		(fp_line
			(start -0.67945 -0.305054)
			(end -0.12065 -0.305054)
			(stroke
				(width 0.1)
				(type default)
			)
			(layer "F.Fab")
		)
		(pad "1" smd circle
			(at -0.40005 0 180)
			(size 0 0)
			(layers "F.Cu" "F.Mask" "F.Paste")
			(net "P5V_AUX")
		)
		(pad "2" smd circle
			(at 0.40005 0 180)
			(size 0 0)
			(layers "F.Cu" "F.Mask" "F.Paste")
			(net "GND")
		)
	)
	(footprint ""
		(layer "F.Cu")
		(at 120.96877 -280.44902 -90)
		(property "Reference" "PC99"
			(at 0 0 270)
			(layer "F.SilkS")
			(hide yes)
			(effects
				(font
					(size 1.27 1.27)
				)
			)
		)
		(property "Value" ""
			(at 0 0 270)
			(layer "F.Fab")
			(effects
				(font
					(size 1.27 1.27)
				)
			)
		)
		(duplicate_pad_numbers_are_jumpers no)
		(fp_line
			(start -0.7874 0.4064)
			(end -0.7874 -0.4064)
			(stroke
				(width 0.1524)
				(type default)
			)
			(layer "F.SilkS")
		)
		(fp_line
			(start 0.7874 0.4064)
			(end -0.7874 0.4064)
			(stroke
				(width 0.1524)
				(type default)
			)
			(layer "F.SilkS")
		)
		(fp_line
			(start -0.7874 -0.4064)
			(end 0.7874 -0.4064)
			(stroke
				(width 0.1524)
				(type default)
			)
			(layer "F.SilkS")
		)
		(fp_line
			(start 0.7874 -0.4064)
			(end 0.7874 0.4064)
			(stroke
				(width 0.1524)
				(type default)
			)
			(layer "F.SilkS")
		)
		(fp_line
			(start -0.67945 0.3048)
			(end -0.67945 -0.305054)
			(stroke
				(width 0.1)
				(type default)
			)
			(layer "F.Fab")
		)
		(fp_line
			(start -0.12065 0.3048)
			(end -0.67945 0.3048)
			(stroke
				(width 0.1)
				(type default)
			)
			(layer "F.Fab")
		)
		(fp_line
			(start 0.120396 0.3048)
			(end 0.120396 0.2794)
			(stroke
				(width 0.1)
				(type default)
			)
			(layer "F.Fab")
		)
		(fp_line
			(start 0.67945 0.3048)
			(end 0.120396 0.3048)
			(stroke
				(width 0.1)
				(type default)
			)
			(layer "F.Fab")
		)
		(fp_line
			(start -0.12065 0.2794)
			(end -0.12065 0.3048)
			(stroke
				(width 0.1)
				(type default)
			)
			(layer "F.Fab")
		)
		(fp_line
			(start 0.120396 0.2794)
			(end -0.12065 0.2794)
			(stroke
				(width 0.1)
				(type default)
			)
			(layer "F.Fab")
		)
		(fp_line
			(start -0.12065 -0.2794)
			(end 0.12065 -0.2794)
			(stroke
				(width 0.1)
				(type default)
			)
			(layer "F.Fab")
		)
		(fp_line
			(start 0.12065 -0.2794)
			(end 0.12065 -0.3048)
			(stroke
				(width 0.1)
				(type default)
			)
			(layer "F.Fab")
		)
		(fp_line
			(start 0.12065 -0.3048)
			(end 0.67945 -0.3048)
			(stroke
				(width 0.1)
				(type default)
			)
			(layer "F.Fab")
		)
		(fp_line
			(start 0.67945 -0.3048)
			(end 0.67945 0.3048)
			(stroke
				(width 0.1)
				(type default)
			)
			(layer "F.Fab")
		)
		(fp_line
			(start -0.67945 -0.305054)
			(end -0.12065 -0.305054)
			(stroke
				(width 0.1)
				(type default)
			)
			(layer "F.Fab")
		)
		(fp_line
			(start -0.12065 -0.305054)
			(end -0.12065 -0.2794)
			(stroke
				(width 0.1)
				(type default)
			)
			(layer "F.Fab")
		)
		(pad "1" smd circle
			(at -0.40005 0 270)
			(size 0 0)
			(layers "F.Cu" "F.Mask" "F.Paste")
			(net "SW_P0V8_PEX1_PHASE1")
		)
		(pad "2" smd circle
			(at 0.40005 0 270)
			(size 0 0)
			(layers "F.Cu" "F.Mask" "F.Paste")
			(net "SW_P0V8_PEX1_BOOT1_R")
		)
	)
	(footprint ""
		(layer "F.Cu")
		(at 284.467808 -54.067456)
		(property "Reference" "PR229"
			(at 0 0 0)
			(layer "F.SilkS")
			(hide yes)
			(effects
				(font
					(size 1.27 1.27)
				)
			)
		)
		(property "Value" ""
			(at 0 0 0)
			(layer "F.Fab")
			(effects
				(font
					(size 1.27 1.27)
				)
			)
		)
		(duplicate_pad_numbers_are_jumpers no)
		(fp_line
			(start -0.7874 -0.4064)
			(end 0.7874 -0.4064)
			(stroke
				(width 0.1524)
				(type default)
			)
			(layer "F.SilkS")
		)
		(fp_line
			(start -0.7874 0.4064)
			(end -0.7874 -0.4064)
			(stroke
				(width 0.1524)
				(type default)
			)
			(layer "F.SilkS")
		)
		(fp_line
			(start 0.7874 -0.4064)
			(end 0.7874 0.4064)
			(stroke
				(width 0.1524)
				(type default)
			)
			(layer "F.SilkS")
		)
		(fp_line
			(start 0.7874 0.4064)
			(end -0.7874 0.4064)
			(stroke
				(width 0.1524)
				(type default)
			)
			(layer "F.SilkS")
		)
		(fp_line
			(start -0.67945 -0.305054)
			(end -0.12065 -0.305054)
			(stroke
				(width 0.1)
				(type default)
			)
			(layer "F.Fab")
		)
		(fp_line
			(start -0.67945 0.3048)
			(end -0.67945 -0.305054)
			(stroke
				(width 0.1)
				(type default)
			)
			(layer "F.Fab")
		)
		(fp_line
			(start -0.12065 -0.305054)
			(end -0.12065 -0.2794)
			(stroke
				(width 0.1)
				(type default)
			)
			(layer "F.Fab")
		)
		(fp_line
			(start -0.12065 -0.2794)
			(end 0.12065 -0.2794)
			(stroke
				(width 0.1)
				(type default)
			)
			(layer "F.Fab")
		)
		(fp_line
			(start -0.12065 0.2794)
			(end -0.12065 0.3048)
			(stroke
				(width 0.1)
				(type default)
			)
			(layer "F.Fab")
		)
		(fp_line
			(start -0.12065 0.3048)
			(end -0.67945 0.3048)
			(stroke
				(width 0.1)
				(type default)
			)
			(layer "F.Fab")
		)
		(fp_line
			(start 0.120396 0.2794)
			(end -0.12065 0.2794)
			(stroke
				(width 0.1)
				(type default)
			)
			(layer "F.Fab")
		)
		(fp_line
			(start 0.120396 0.3048)
			(end 0.120396 0.2794)
			(stroke
				(width 0.1)
				(type default)
			)
			(layer "F.Fab")
		)
		(fp_line
			(start 0.12065 -0.3048)
			(end 0.67945 -0.3048)
			(stroke
				(width 0.1)
				(type default)
			)
			(layer "F.Fab")
		)
		(fp_line
			(start 0.12065 -0.2794)
			(end 0.12065 -0.3048)
			(stroke
				(width 0.1)
				(type default)
			)
			(layer "F.Fab")
		)
		(fp_line
			(start 0.67945 -0.3048)
			(end 0.67945 0.3048)
			(stroke
				(width 0.1)
				(type default)
			)
			(layer "F.Fab")
		)
		(fp_line
			(start 0.67945 0.3048)
			(end 0.120396 0.3048)
			(stroke
				(width 0.1)
				(type default)
			)
			(layer "F.Fab")
		)
		(pad "1" smd circle
			(at -0.40005 0)
			(size 0 0)
			(layers "F.Cu" "F.Mask" "F.Paste")
			(net "P12V_SSD9_OCP")
		)
		(pad "2" smd circle
			(at 0.40005 0)
			(size 0 0)
			(layers "F.Cu" "F.Mask" "F.Paste")
			(net "GND")
		)
	)
	(footprint ""
		(layer "F.Cu")
		(at 241.550698 -257.975862 -90)
		(property "Reference" "R6526"
			(at 0 0 270)
			(layer "F.SilkS")
			(hide yes)
			(effects
				(font
					(size 1.27 1.27)
				)
			)
		)
		(property "Value" ""
			(at 0 0 270)
			(layer "F.Fab")
			(effects
				(font
					(size 1.27 1.27)
				)
			)
		)
		(duplicate_pad_numbers_are_jumpers no)
		(fp_line
			(start -0.7874 0.4064)
			(end -0.7874 -0.4064)
			(stroke
				(width 0.1524)
				(type default)
			)
			(layer "F.SilkS")
		)
		(fp_line
			(start 0.7874 0.4064)
			(end -0.7874 0.4064)
			(stroke
				(width 0.1524)
				(type default)
			)
			(layer "F.SilkS")
		)
		(fp_line
			(start -0.7874 -0.4064)
			(end 0.7874 -0.4064)
			(stroke
				(width 0.1524)
				(type default)
			)
			(layer "F.SilkS")
		)
		(fp_line
			(start 0.7874 -0.4064)
			(end 0.7874 0.4064)
			(stroke
				(width 0.1524)
				(type default)
			)
			(layer "F.SilkS")
		)
		(fp_line
			(start -0.67945 0.3048)
			(end -0.67945 -0.305054)
			(stroke
				(width 0.1)
				(type default)
			)
			(layer "F.Fab")
		)
		(fp_line
			(start -0.12065 0.3048)
			(end -0.67945 0.3048)
			(stroke
				(width 0.1)
				(type default)
			)
			(layer "F.Fab")
		)
		(fp_line
			(start 0.120396 0.3048)
			(end 0.120396 0.2794)
			(stroke
				(width 0.1)
				(type default)
			)
			(layer "F.Fab")
		)
		(fp_line
			(start 0.67945 0.3048)
			(end 0.120396 0.3048)
			(stroke
				(width 0.1)
				(type default)
			)
			(layer "F.Fab")
		)
		(fp_line
			(start -0.12065 0.2794)
			(end -0.12065 0.3048)
			(stroke
				(width 0.1)
				(type default)
			)
			(layer "F.Fab")
		)
		(fp_line
			(start 0.120396 0.2794)
			(end -0.12065 0.2794)
			(stroke
				(width 0.1)
				(type default)
			)
			(layer "F.Fab")
		)
		(fp_line
			(start -0.12065 -0.2794)
			(end 0.12065 -0.2794)
			(stroke
				(width 0.1)
				(type default)
			)
			(layer "F.Fab")
		)
		(fp_line
			(start 0.12065 -0.2794)
			(end 0.12065 -0.3048)
			(stroke
				(width 0.1)
				(type default)
			)
			(layer "F.Fab")
		)
		(fp_line
			(start 0.12065 -0.3048)
			(end 0.67945 -0.3048)
			(stroke
				(width 0.1)
				(type default)
			)
			(layer "F.Fab")
		)
		(fp_line
			(start 0.67945 -0.3048)
			(end 0.67945 0.3048)
			(stroke
				(width 0.1)
				(type default)
			)
			(layer "F.Fab")
		)
		(fp_line
			(start -0.67945 -0.305054)
			(end -0.12065 -0.305054)
			(stroke
				(width 0.1)
				(type default)
			)
			(layer "F.Fab")
		)
		(fp_line
			(start -0.12065 -0.305054)
			(end -0.12065 -0.2794)
			(stroke
				(width 0.1)
				(type default)
			)
			(layer "F.Fab")
		)
		(pad "1" smd circle
			(at -0.40005 0 270)
			(size 0 0)
			(layers "F.Cu" "F.Mask" "F.Paste")
			(net "P1V25_SERDES_VDDPLL_PEX2")
		)
		(pad "2" smd circle
			(at 0.40005 0 270)
			(size 0 0)
			(layers "F.Cu" "F.Mask" "F.Paste")
			(net "P1V25_SERDES_VDDPLL_PEX2_C5")
		)
	)
)
